# S9S_MB_2U (Grand Teton) — schematic netlist excerpt (pin names and nets, part order shuffled) for the footprints in the layout excerpt that follows; sources: Cadence DE-HDL packaged netlist, KiCad conversion of 03242023_DA0F0TMBIJ0_F0T_Motherboard_J_brd_V01_OCP.brd

R1648  Q_RES  0 5% EMPTY  pkg 0402LF  page 236 : A = SMB_S3M_CPU0_3V3AUX_SDA ; B = SMB_S3M_CPU1_3V3AUX_SDA
PR3853  Q_RES  120K 1% CHIP  pkg 0402LF  page 163 : A = P12V_AUX ; B = P12V_OCP_OV_FB_2

(kicad_pcb
	(version 20260206)
	(generator "pcbnew")
	(generator_version "10.0")
	(general
		(thickness 1.6)
		(legacy_teardrops no)
	)
	(paper "A4")
	(title_block
		(title "03242023_DA0F0TMBIJ0_F0T_Motherboard_J_brd_V01_OCP.brd")
		(comment 1 "Grand Teton / footprints 2681-2682 of 6105")
	)
	(layers
		(0 "F.Cu" signal "TOP")
		(4 "In1.Cu" signal "GND")
		(6 "In2.Cu" signal "IN1")
		(8 "In3.Cu" signal "GND1")
		(10 "In4.Cu" signal "IN2")
		(12 "In5.Cu" signal "GND2")
		(14 "In6.Cu" signal "IN3")
		(16 "In7.Cu" signal "GND3")
		(18 "In8.Cu" signal "VCC")
		(20 "In9.Cu" signal "VCC1")
		(22 "In10.Cu" signal "GND4")
		(24 "In11.Cu" signal "IN4")
		(26 "In12.Cu" signal "GND5")
		(28 "In13.Cu" signal "IN5")
		(30 "In14.Cu" signal "GND6")
		(32 "In15.Cu" signal "IN6")
		(34 "In16.Cu" signal "GND7")
		(2 "B.Cu" signal "BOTTOM")
		(9 "F.Adhes" user "F.Adhesive")
		(11 "B.Adhes" user "B.Adhesive")
		(13 "F.Paste" user "Package Geometry/Pastemask Top")
		(15 "B.Paste" user "Package Geometry/Pastemask Bottom")
		(5 "F.SilkS" user "Ref Des/Silkscreen Top")
		(7 "B.SilkS" user "Ref Des/Silkscreen Bottom")
		(1 "F.Mask" user "Board Geometry/Soldermask Top")
		(3 "B.Mask" user "Board Geometry/Soldermask Bottom")
		(17 "Dwgs.User" user "User.Drawings")
		(19 "Cmts.User" user "User.Comments")
		(21 "Eco1.User" user "User.Eco1")
		(23 "Eco2.User" user "User.Eco2")
		(25 "Edge.Cuts" user "Board Geometry/Outline")
		(27 "Margin" user)
		(31 "F.CrtYd" user "Package Geometry/Place Bound Top")
		(29 "B.CrtYd" user "Package Geometry/Place Bound Bottom")
		(35 "F.Fab" user "Ref Des/Assembly Top")
		(33 "B.Fab" user "Ref Des/Assembly Bottom")
	)
	(footprint ""
		(layer "F.Cu")
		(at 391.08888 -148.808948 -90)
		(property "Reference" "R1648"
			(at 0 0 270)
			(layer "F.SilkS")
			(hide yes)
			(effects
				(font
					(size 1.27 1.27)
				)
			)
		)
		(property "Value" ""
			(at 0 0 270)
			(layer "F.Fab")
			(effects
				(font
					(size 1.27 1.27)
				)
			)
		)
		(duplicate_pad_numbers_are_jumpers no)
		(fp_line
			(start -0.7874 0.4064)
			(end -0.7874 -0.4064)
			(stroke
				(width 0.1524)
				(type default)
			)
			(layer "F.SilkS")
		)
		(fp_line
			(start 0.7874 0.4064)
			(end -0.7874 0.4064)
			(stroke
				(width 0.1524)
				(type default)
			)
			(layer "F.SilkS")
		)
		(fp_line
			(start -0.7874 -0.4064)
			(end 0.7874 -0.4064)
			(stroke
				(width 0.1524)
				(type default)
			)
			(layer "F.SilkS")
		)
		(fp_line
			(start 0.7874 -0.4064)
			(end 0.7874 0.4064)
			(stroke
				(width 0.1524)
				(type default)
			)
			(layer "F.SilkS")
		)
		(fp_line
			(start -0.67945 0.3048)
			(end -0.67945 -0.305054)
			(stroke
				(width 0.1)
				(type default)
			)
			(layer "F.Fab")
		)
		(fp_line
			(start -0.12065 0.3048)
			(end -0.67945 0.3048)
			(stroke
				(width 0.1)
				(type default)
			)
			(layer "F.Fab")
		)
		(fp_line
			(start 0.120396 0.3048)
			(end 0.120396 0.2794)
			(stroke
				(width 0.1)
				(type default)
			)
			(layer "F.Fab")
		)
		(fp_line
			(start 0.67945 0.3048)
			(end 0.120396 0.3048)
			(stroke
				(width 0.1)
				(type default)
			)
			(layer "F.Fab")
		)
		(fp_line
			(start -0.12065 0.2794)
			(end -0.12065 0.3048)
			(stroke
				(width 0.1)
				(type default)
			)
			(layer "F.Fab")
		)
		(fp_line
			(start 0.120396 0.2794)
			(end -0.12065 0.2794)
			(stroke
				(width 0.1)
				(type default)
			)
			(layer "F.Fab")
		)
		(fp_line
			(start -0.12065 -0.2794)
			(end 0.12065 -0.2794)
			(stroke
				(width 0.1)
				(type default)
			)
			(layer "F.Fab")
		)
		(fp_line
			(start 0.12065 -0.2794)
			(end 0.12065 -0.3048)
			(stroke
				(width 0.1)
				(type default)
			)
			(layer "F.Fab")
		)
		(fp_line
			(start 0.12065 -0.3048)
			(end 0.67945 -0.3048)
			(stroke
				(width 0.1)
				(type default)
			)
			(layer "F.Fab")
		)
		(fp_line
			(start 0.67945 -0.3048)
			(end 0.67945 0.3048)
			(stroke
				(width 0.1)
				(type default)
			)
			(layer "F.Fab")
		)
		(fp_line
			(start -0.67945 -0.305054)
			(end -0.12065 -0.305054)
			(stroke
				(width 0.1)
				(type default)
			)
			(layer "F.Fab")
		)
		(fp_line
			(start -0.12065 -0.305054)
			(end -0.12065 -0.2794)
			(stroke
				(width 0.1)
				(type default)
			)
			(layer "F.Fab")
		)
		(pad "1" smd circle
			(at -0.40005 0 270)
			(size 0 0)
			(layers "F.Cu" "F.Mask" "F.Paste")
			(net "SMB_S3M_CPU0_3V3AUX_SDA")
		)
		(pad "2" smd circle
			(at 0.40005 0 270)
			(size 0 0)
			(layers "F.Cu" "F.Mask" "F.Paste")
			(net "SMB_S3M_CPU1_3V3AUX_SDA")
		)
	)
	(footprint ""
		(layer "F.Cu")
		(at 62.861698 -26.99004 90)
		(property "Reference" "PR3853"
			(at 0 0 90)
			(layer "F.SilkS")
			(hide yes)
			(effects
				(font
					(size 1.27 1.27)
				)
			)
		)
		(property "Value" ""
			(at 0 0 90)
			(layer "F.Fab")
			(effects
				(font
					(size 1.27 1.27)
				)
			)
		)
		(duplicate_pad_numbers_are_jumpers no)
		(fp_line
			(start 0.7874 -0.4064)
			(end 0.7874 0.4064)
			(stroke
				(width 0.1524)
				(type default)
			)
			(layer "F.SilkS")
		)
		(fp_line
			(start -0.7874 -0.4064)
			(end 0.7874 -0.4064)
			(stroke
				(width 0.1524)
				(type default)
			)
			(layer "F.SilkS")
		)
		(fp_line
			(start 0.7874 0.4064)
			(end -0.7874 0.4064)
			(stroke
				(width 0.1524)
				(type default)
			)
			(layer "F.SilkS")
		)
		(fp_line
			(start -0.7874 0.4064)
			(end -0.7874 -0.4064)
			(stroke
				(width 0.1524)
				(type default)
			)
			(layer "F.SilkS")
		)
		(fp_line
			(start -0.12065 -0.305054)
			(end -0.12065 -0.2794)
			(stroke
				(width 0.1)
				(type default)
			)
			(layer "F.Fab")
		)
		(fp_line
			(start -0.67945 -0.305054)
			(end -0.12065 -0.305054)
			(stroke
				(width 0.1)
				(type default)
			)
			(layer "F.Fab")
		)
		(fp_line
			(start 0.67945 -0.3048)
			(end 0.67945 0.3048)
			(stroke
				(width 0.1)
				(type default)
			)
			(layer "F.Fab")
		)
		(fp_line
			(start 0.12065 -0.3048)
			(end 0.67945 -0.3048)
			(stroke
				(width 0.1)
				(type default)
			)
			(layer "F.Fab")
		)
		(fp_line
			(start 0.12065 -0.2794)
			(end 0.12065 -0.3048)
			(stroke
				(width 0.1)
				(type default)
			)
			(layer "F.Fab")
		)
		(fp_line
			(start -0.12065 -0.2794)
			(end 0.12065 -0.2794)
			(stroke
				(width 0.1)
				(type default)
			)
			(layer "F.Fab")
		)
		(fp_line
			(start 0.120396 0.2794)
			(end -0.12065 0.2794)
			(stroke
				(width 0.1)
				(type default)
			)
			(layer "F.Fab")
		)
		(fp_line
			(start -0.12065 0.2794)
			(end -0.12065 0.3048)
			(stroke
				(width 0.1)
				(type default)
			)
			(layer "F.Fab")
		)
		(fp_line
			(start 0.67945 0.3048)
			(end 0.120396 0.3048)
			(stroke
				(width 0.1)
				(type default)
			)
			(layer "F.Fab")
		)
		(fp_line
			(start 0.120396 0.3048)
			(end 0.120396 0.2794)
			(stroke
				(width 0.1)
				(type default)
			)
			(layer "F.Fab")
		)
		(fp_line
			(start -0.12065 0.3048)
			(end -0.67945 0.3048)
			(stroke
				(width 0.1)
				(type default)
			)
			(layer "F.Fab")
		)
		(fp_line
			(start -0.67945 0.3048)
			(end -0.67945 -0.305054)
			(stroke
				(width 0.1)
				(type default)
			)
			(layer "F.Fab")
		)
		(pad "1" smd circle
			(at -0.40005 0 90)
			(size 0 0)
			(layers "F.Cu" "F.Mask" "F.Paste")
			(net "P12V_AUX")
		)
		(pad "2" smd circle
			(at 0.40005 0 90)
			(size 0 0)
			(layers "F.Cu" "F.Mask" "F.Paste")
			(net "P12V_OCP_OV_FB_2")
		)
	)
)
